# SCM (Grand Teton) — schematic netlist excerpt (pin names and nets, part order shuffled) for the footprints in the layout excerpt that follows; sources: Cadence DE-HDL packaged netlist, KiCad conversion of 12092022_DA0F0TMDCD0_F0T_Management_Board_D_brd_V3_OCP.brd

C156  Q_CAP  0.001UF 50V 10% EMPTY  pkg C0402  page 56 : A = PWRGD_P1V0_AUX_R ; B = GND
R774  Q_RES  4.7K 1% CHIP  pkg 0402LF  page 13 : A = P3V3_AUX ; B = FM_SLPS3_GF_N

(kicad_pcb
	(version 20260206)
	(generator "pcbnew")
	(generator_version "10.0")
	(general
		(thickness 1.6)
		(legacy_teardrops no)
	)
	(paper "A4")
	(title_block
		(title "12092022_DA0F0TMDCD0_F0T_Management_Board_D_brd_V3_OCP.brd")
		(comment 1 "Grand Teton / footprints 139-140 of 1440")
	)
	(layers
		(0 "F.Cu" signal "TOP")
		(4 "In1.Cu" signal "GND")
		(6 "In2.Cu" signal "IN1")
		(8 "In3.Cu" signal "GND1")
		(10 "In4.Cu" signal "IN2")
		(12 "In5.Cu" signal "VCC")
		(14 "In6.Cu" signal "VCC1")
		(16 "In7.Cu" signal "IN3")
		(18 "In8.Cu" signal "GND2")
		(20 "In9.Cu" signal "IN4")
		(22 "In10.Cu" signal "GND3")
		(2 "B.Cu" signal "BOTTOM")
		(9 "F.Adhes" user "F.Adhesive")
		(11 "B.Adhes" user "B.Adhesive")
		(13 "F.Paste" user "Package Geometry/Pastemask Top")
		(15 "B.Paste" user "Package Geometry/Pastemask Bottom")
		(5 "F.SilkS" user "Ref Des/Silkscreen Top")
		(7 "B.SilkS" user "Ref Des/Silkscreen Bottom")
		(1 "F.Mask" user "Board Geometry/Soldermask Top")
		(3 "B.Mask" user "Board Geometry/Soldermask Bottom")
		(17 "Dwgs.User" user "User.Drawings")
		(19 "Cmts.User" user "User.Comments")
		(21 "Eco1.User" user "User.Eco1")
		(23 "Eco2.User" user "User.Eco2")
		(25 "Edge.Cuts" user "Board Geometry/Outline")
		(27 "Margin" user)
		(31 "F.CrtYd" user "Package Geometry/Place Bound Top")
		(29 "B.CrtYd" user "Package Geometry/Place Bound Bottom")
		(35 "F.Fab" user "Ref Des/Assembly Top")
		(33 "B.Fab" user "Ref Des/Assembly Bottom")
	)
	(footprint ""
		(layer "F.Cu")
		(at 24.4856 -33.909 90)
		(property "Reference" "C156"
			(at 0 0 90)
			(layer "F.SilkS")
			(hide yes)
			(effects
				(font
					(size 1.27 1.27)
				)
			)
		)
		(property "Value" ""
			(at 0 0 90)
			(layer "F.Fab")
			(effects
				(font
					(size 1.27 1.27)
				)
			)
		)
		(duplicate_pad_numbers_are_jumpers no)
		(fp_line
			(start 0.7874 -0.4064)
			(end 0.7874 0.4064)
			(stroke
				(width 0.1524)
				(type default)
			)
			(layer "F.SilkS")
		)
		(fp_line
			(start -0.7874 -0.4064)
			(end 0.7874 -0.4064)
			(stroke
				(width 0.1524)
				(type default)
			)
			(layer "F.SilkS")
		)
		(fp_line
			(start 0.7874 0.4064)
			(end -0.7874 0.4064)
			(stroke
				(width 0.1524)
				(type default)
			)
			(layer "F.SilkS")
		)
		(fp_line
			(start -0.7874 0.4064)
			(end -0.7874 -0.4064)
			(stroke
				(width 0.1524)
				(type default)
			)
			(layer "F.SilkS")
		)
		(fp_line
			(start -0.12065 -0.305054)
			(end -0.12065 -0.2794)
			(stroke
				(width 0.1)
				(type default)
			)
			(layer "F.Fab")
		)
		(fp_line
			(start -0.67945 -0.305054)
			(end -0.12065 -0.305054)
			(stroke
				(width 0.1)
				(type default)
			)
			(layer "F.Fab")
		)
		(fp_line
			(start 0.67945 -0.3048)
			(end 0.67945 0.3048)
			(stroke
				(width 0.1)
				(type default)
			)
			(layer "F.Fab")
		)
		(fp_line
			(start 0.12065 -0.3048)
			(end 0.67945 -0.3048)
			(stroke
				(width 0.1)
				(type default)
			)
			(layer "F.Fab")
		)
		(fp_line
			(start 0.12065 -0.2794)
			(end 0.12065 -0.3048)
			(stroke
				(width 0.1)
				(type default)
			)
			(layer "F.Fab")
		)
		(fp_line
			(start -0.12065 -0.2794)
			(end 0.12065 -0.2794)
			(stroke
				(width 0.1)
				(type default)
			)
			(layer "F.Fab")
		)
		(fp_line
			(start 0.120396 0.2794)
			(end -0.12065 0.2794)
			(stroke
				(width 0.1)
				(type default)
			)
			(layer "F.Fab")
		)
		(fp_line
			(start -0.12065 0.2794)
			(end -0.12065 0.3048)
			(stroke
				(width 0.1)
				(type default)
			)
			(layer "F.Fab")
		)
		(fp_line
			(start 0.67945 0.3048)
			(end 0.120396 0.3048)
			(stroke
				(width 0.1)
				(type default)
			)
			(layer "F.Fab")
		)
		(fp_line
			(start 0.120396 0.3048)
			(end 0.120396 0.2794)
			(stroke
				(width 0.1)
				(type default)
			)
			(layer "F.Fab")
		)
		(fp_line
			(start -0.12065 0.3048)
			(end -0.67945 0.3048)
			(stroke
				(width 0.1)
				(type default)
			)
			(layer "F.Fab")
		)
		(fp_line
			(start -0.67945 0.3048)
			(end -0.67945 -0.305054)
			(stroke
				(width 0.1)
				(type default)
			)
			(layer "F.Fab")
		)
		(pad "1" smd circle
			(at -0.40005 0 90)
			(size 0 0)
			(layers "F.Cu" "F.Mask" "F.Paste")
			(net "PWRGD_P1V0_AUX_R")
		)
		(pad "2" smd circle
			(at 0.40005 0 90)
			(size 0 0)
			(layers "F.Cu" "F.Mask" "F.Paste")
			(net "GND")
		)
	)
	(footprint ""
		(layer "F.Cu")
		(at 50.3174 -68.2498)
		(property "Reference" "R774"
			(at 0 0 0)
			(layer "F.SilkS")
			(hide yes)
			(effects
				(font
					(size 1.27 1.27)
				)
			)
		)
		(property "Value" ""
			(at 0 0 0)
			(layer "F.Fab")
			(effects
				(font
					(size 1.27 1.27)
				)
			)
		)
		(duplicate_pad_numbers_are_jumpers no)
		(fp_line
			(start -0.7874 -0.4064)
			(end 0.7874 -0.4064)
			(stroke
				(width 0.1524)
				(type default)
			)
			(layer "F.SilkS")
		)
		(fp_line
			(start -0.7874 0.4064)
			(end -0.7874 -0.4064)
			(stroke
				(width 0.1524)
				(type default)
			)
			(layer "F.SilkS")
		)
		(fp_line
			(start 0.7874 -0.4064)
			(end 0.7874 0.4064)
			(stroke
				(width 0.1524)
				(type default)
			)
			(layer "F.SilkS")
		)
		(fp_line
			(start 0.7874 0.4064)
			(end -0.7874 0.4064)
			(stroke
				(width 0.1524)
				(type default)
			)
			(layer "F.SilkS")
		)
		(fp_line
			(start -0.67945 -0.305054)
			(end -0.12065 -0.305054)
			(stroke
				(width 0.1)
				(type default)
			)
			(layer "F.Fab")
		)
		(fp_line
			(start -0.67945 0.3048)
			(end -0.67945 -0.305054)
			(stroke
				(width 0.1)
				(type default)
			)
			(layer "F.Fab")
		)
		(fp_line
			(start -0.12065 -0.305054)
			(end -0.12065 -0.2794)
			(stroke
				(width 0.1)
				(type default)
			)
			(layer "F.Fab")
		)
		(fp_line
			(start -0.12065 -0.2794)
			(end 0.12065 -0.2794)
			(stroke
				(width 0.1)
				(type default)
			)
			(layer "F.Fab")
		)
		(fp_line
			(start -0.12065 0.2794)
			(end -0.12065 0.3048)
			(stroke
				(width 0.1)
				(type default)
			)
			(layer "F.Fab")
		)
		(fp_line
			(start -0.12065 0.3048)
			(end -0.67945 0.3048)
			(stroke
				(width 0.1)
				(type default)
			)
			(layer "F.Fab")
		)
		(fp_line
			(start 0.120396 0.2794)
			(end -0.12065 0.2794)
			(stroke
				(width 0.1)
				(type default)
			)
			(layer "F.Fab")
		)
		(fp_line
			(start 0.120396 0.3048)
			(end 0.120396 0.2794)
			(stroke
				(width 0.1)
				(type default)
			)
			(layer "F.Fab")
		)
		(fp_line
			(start 0.12065 -0.3048)
			(end 0.67945 -0.3048)
			(stroke
				(width 0.1)
				(type default)
			)
			(layer "F.Fab")
		)
		(fp_line
			(start 0.12065 -0.2794)
			(end 0.12065 -0.3048)
			(stroke
				(width 0.1)
				(type default)
			)
			(layer "F.Fab")
		)
		(fp_line
			(start 0.67945 -0.3048)
			(end 0.67945 0.3048)
			(stroke
				(width 0.1)
				(type default)
			)
			(layer "F.Fab")
		)
		(fp_line
			(start 0.67945 0.3048)
			(end 0.120396 0.3048)
			(stroke
				(width 0.1)
				(type default)
			)
			(layer "F.Fab")
		)
		(pad "1" smd circle
			(at -0.40005 0)
			(size 0 0)
			(layers "F.Cu" "F.Mask" "F.Paste")
			(net "P3V3_AUX")
		)
		(pad "2" smd circle
			(at 0.40005 0)
			(size 0 0)
			(layers "F.Cu" "F.Mask" "F.Paste")
			(net "FM_SLPS3_GF_N")
		)
	)
)
